# T6G (Grand Teton) — schematic netlist excerpt (pin names and nets, part order shuffled) for the footprints in the layout excerpt that follows; sources: Cadence DE-HDL packaged netlist, KiCad conversion of 04192023_DAF0TMB3IC0_F0TG_MB_C_brd_V02_OCP.brd

PC6531  Q_CAP  22UF 4V 20% X6S  pkg C0805  page 361 : A = P1V8_CPU1_RT_1D ; B = GND
PC90_2  Q_CAP  22UF 16V 20% X6S  pkg C0805  page 201 : A = SW_P12V_AUX_PVDDCR_CPU1_P0_FLT ; B = GND
C1923  Q_CAP  0.1UF 25V 10% X7R  pkg 0402  page 144 : A = P3V3_M2_0 ; B = GND

(kicad_pcb
	(version 20260206)
	(generator "pcbnew")
	(generator_version "10.0")
	(general
		(thickness 1.6)
		(legacy_teardrops no)
	)
	(paper "A4")
	(title_block
		(title "04192023_DAF0TMB3IC0_F0TG_MB_C_brd_V02_OCP.brd")
		(comment 1 "Grand Teton / footprints 5415-5417 of 8354")
	)
	(layers
		(0 "F.Cu" signal "TOP")
		(4 "In1.Cu" signal "GND")
		(6 "In2.Cu" signal "IN1")
		(8 "In3.Cu" signal "GND1")
		(10 "In4.Cu" signal "IN2")
		(12 "In5.Cu" signal "GND2")
		(14 "In6.Cu" signal "IN3")
		(16 "In7.Cu" signal "GND3")
		(18 "In8.Cu" signal "VCC")
		(20 "In9.Cu" signal "VCC1")
		(22 "In10.Cu" signal "GND4")
		(24 "In11.Cu" signal "IN4")
		(26 "In12.Cu" signal "GND5")
		(28 "In13.Cu" signal "IN5")
		(30 "In14.Cu" signal "GND6")
		(32 "In15.Cu" signal "IN6")
		(34 "In16.Cu" signal "GND7")
		(2 "B.Cu" signal "BOTTOM")
		(9 "F.Adhes" user "F.Adhesive")
		(11 "B.Adhes" user "B.Adhesive")
		(13 "F.Paste" user "Package Geometry/Pastemask Top")
		(15 "B.Paste" user "Package Geometry/Pastemask Bottom")
		(5 "F.SilkS" user "Ref Des/Silkscreen Top")
		(7 "B.SilkS" user "Ref Des/Silkscreen Bottom")
		(1 "F.Mask" user "Board Geometry/Soldermask Top")
		(3 "B.Mask" user "Board Geometry/Soldermask Bottom")
		(17 "Dwgs.User" user "User.Drawings")
		(19 "Cmts.User" user "User.Comments")
		(21 "Eco1.User" user "User.Eco1")
		(23 "Eco2.User" user "User.Eco2")
		(25 "Edge.Cuts" user "Board Geometry/Outline")
		(27 "Margin" user)
		(31 "F.CrtYd" user "Package Geometry/Place Bound Top")
		(29 "B.CrtYd" user "Package Geometry/Place Bound Bottom")
		(35 "F.Fab" user "Ref Des/Assembly Top")
		(33 "B.Fab" user "Ref Des/Assembly Bottom")
	)
	(footprint ""
		(layer "B.Cu")
		(at 329.95108 -335.055972 90)
		(property "Reference" "PC90_2"
			(at 0 0 90)
			(layer "B.SilkS")
			(hide yes)
			(effects
				(font
					(size 1.27 1.27)
				)
				(justify mirror)
			)
		)
		(property "Value" ""
			(at 0 0 90)
			(layer "B.Fab")
			(effects
				(font
					(size 1.27 1.27)
				)
				(justify mirror)
			)
		)
		(duplicate_pad_numbers_are_jumpers no)
		(fp_line
			(start 1.524 -0.762)
			(end -1.524 -0.762)
			(stroke
				(width 0.1524)
				(type default)
			)
			(layer "B.SilkS")
		)
		(fp_line
			(start -1.524 -0.762)
			(end -1.524 0.762)
			(stroke
				(width 0.1524)
				(type default)
			)
			(layer "B.SilkS")
		)
		(fp_line
			(start 1.524 0.762)
			(end 1.524 -0.762)
			(stroke
				(width 0.1524)
				(type default)
			)
			(layer "B.SilkS")
		)
		(fp_line
			(start -1.524 0.762)
			(end 1.524 0.762)
			(stroke
				(width 0.1524)
				(type default)
			)
			(layer "B.SilkS")
		)
		(fp_line
			(start 1.1049 -0.724916)
			(end 1.1049 0.724916)
			(stroke
				(width 0.1)
				(type default)
			)
			(layer "B.Fab")
		)
		(fp_line
			(start -1.1049 -0.724916)
			(end 1.1049 -0.724916)
			(stroke
				(width 0.1)
				(type default)
			)
			(layer "B.Fab")
		)
		(fp_line
			(start 1.1049 0.724916)
			(end -1.1049 0.724916)
			(stroke
				(width 0.1)
				(type default)
			)
			(layer "B.Fab")
		)
		(fp_line
			(start -1.1049 0.724916)
			(end -1.1049 -0.724916)
			(stroke
				(width 0.1)
				(type default)
			)
			(layer "B.Fab")
		)
		(pad "1" smd rect
			(at 0.889 0 90)
			(size 1.016 1.27)
			(layers "B.Cu" "B.Mask" "B.Paste")
			(net "SW_P12V_AUX_PVDDCR_CPU1_P0_FLT")
		)
		(pad "2" smd rect
			(at -0.889 0 90)
			(size 1.016 1.27)
			(layers "B.Cu" "B.Mask" "B.Paste")
			(net "GND")
		)
	)
	(footprint ""
		(layer "B.Cu")
		(at 169.66692 -53.431948 180)
		(property "Reference" "C1923"
			(at 0 0 0)
			(layer "B.SilkS")
			(hide yes)
			(effects
				(font
					(size 1.27 1.27)
				)
				(justify mirror)
			)
		)
		(property "Value" ""
			(at 0 0 0)
			(layer "B.Fab")
			(effects
				(font
					(size 1.27 1.27)
				)
				(justify mirror)
			)
		)
		(duplicate_pad_numbers_are_jumpers no)
		(fp_line
			(start 0.7874 0.4064)
			(end 0.7874 -0.4064)
			(stroke
				(width 0.1524)
				(type default)
			)
			(layer "B.SilkS")
		)
		(fp_line
			(start 0.7874 -0.4064)
			(end -0.7874 -0.4064)
			(stroke
				(width 0.1524)
				(type default)
			)
			(layer "B.SilkS")
		)
		(fp_line
			(start -0.7874 0.4064)
			(end 0.7874 0.4064)
			(stroke
				(width 0.1524)
				(type default)
			)
			(layer "B.SilkS")
		)
		(fp_line
			(start -0.7874 -0.4064)
			(end -0.7874 0.4064)
			(stroke
				(width 0.1524)
				(type default)
			)
			(layer "B.SilkS")
		)
		(fp_line
			(start 0.67945 0.3048)
			(end 0.67945 -0.305054)
			(stroke
				(width 0.1)
				(type default)
			)
			(layer "B.Fab")
		)
		(fp_line
			(start 0.67945 -0.305054)
			(end 0.12065 -0.305054)
			(stroke
				(width 0.1)
				(type default)
			)
			(layer "B.Fab")
		)
		(fp_line
			(start 0.12065 0.3048)
			(end 0.67945 0.3048)
			(stroke
				(width 0.1)
				(type default)
			)
			(layer "B.Fab")
		)
		(fp_line
			(start 0.12065 0.2794)
			(end 0.12065 0.3048)
			(stroke
				(width 0.1)
				(type default)
			)
			(layer "B.Fab")
		)
		(fp_line
			(start 0.12065 -0.2794)
			(end -0.12065 -0.2794)
			(stroke
				(width 0.1)
				(type default)
			)
			(layer "B.Fab")
		)
		(fp_line
			(start 0.12065 -0.305054)
			(end 0.12065 -0.2794)
			(stroke
				(width 0.1)
				(type default)
			)
			(layer "B.Fab")
		)
		(fp_line
			(start -0.120396 0.3048)
			(end -0.120396 0.2794)
			(stroke
				(width 0.1)
				(type default)
			)
			(layer "B.Fab")
		)
		(fp_line
			(start -0.120396 0.2794)
			(end 0.12065 0.2794)
			(stroke
				(width 0.1)
				(type default)
			)
			(layer "B.Fab")
		)
		(fp_line
			(start -0.12065 -0.2794)
			(end -0.12065 -0.3048)
			(stroke
				(width 0.1)
				(type default)
			)
			(layer "B.Fab")
		)
		(fp_line
			(start -0.12065 -0.3048)
			(end -0.67945 -0.3048)
			(stroke
				(width 0.1)
				(type default)
			)
			(layer "B.Fab")
		)
		(fp_line
			(start -0.67945 0.3048)
			(end -0.120396 0.3048)
			(stroke
				(width 0.1)
				(type default)
			)
			(layer "B.Fab")
		)
		(fp_line
			(start -0.67945 -0.3048)
			(end -0.67945 0.3048)
			(stroke
				(width 0.1)
				(type default)
			)
			(layer "B.Fab")
		)
		(pad "1" smd circle
			(at 0.40005 0)
			(size 0 0)
			(layers "B.Cu" "B.Mask" "B.Paste")
			(net "P3V3_M2_0")
		)
		(pad "2" smd circle
			(at -0.40005 0)
			(size 0 0)
			(layers "B.Cu" "B.Mask" "B.Paste")
			(net "GND")
		)
	)
	(footprint ""
		(layer "B.Cu")
		(at 224.999042 -315.95568 -90)
		(property "Reference" "PC6531"
			(at 0 0 90)
			(layer "B.SilkS")
			(hide yes)
			(effects
				(font
					(size 1.27 1.27)
				)
				(justify mirror)
			)
		)
		(property "Value" ""
			(at 0 0 90)
			(layer "B.Fab")
			(effects
				(font
					(size 1.27 1.27)
				)
				(justify mirror)
			)
		)
		(duplicate_pad_numbers_are_jumpers no)
		(fp_line
			(start -1.524 0.762)
			(end 1.524 0.762)
			(stroke
				(width 0.1524)
				(type default)
			)
			(layer "B.SilkS")
		)
		(fp_line
			(start 1.524 0.762)
			(end 1.524 -0.762)
			(stroke
				(width 0.1524)
				(type default)
			)
			(layer "B.SilkS")
		)
		(fp_line
			(start -1.524 -0.762)
			(end -1.524 0.762)
			(stroke
				(width 0.1524)
				(type default)
			)
			(layer "B.SilkS")
		)
		(fp_line
			(start 1.524 -0.762)
			(end -1.524 -0.762)
			(stroke
				(width 0.1524)
				(type default)
			)
			(layer "B.SilkS")
		)
		(fp_line
			(start -1.1049 0.724916)
			(end -1.1049 -0.724916)
			(stroke
				(width 0.1)
				(type default)
			)
			(layer "B.Fab")
		)
		(fp_line
			(start 1.1049 0.724916)
			(end -1.1049 0.724916)
			(stroke
				(width 0.1)
				(type default)
			)
			(layer "B.Fab")
		)
		(fp_line
			(start -1.1049 -0.724916)
			(end 1.1049 -0.724916)
			(stroke
				(width 0.1)
				(type default)
			)
			(layer "B.Fab")
		)
		(fp_line
			(start 1.1049 -0.724916)
			(end 1.1049 0.724916)
			(stroke
				(width 0.1)
				(type default)
			)
			(layer "B.Fab")
		)
		(pad "1" smd rect
			(at 0.889 0 270)
			(size 1.016 1.27)
			(layers "B.Cu" "B.Mask" "B.Paste")
			(net "P1V8_CPU1_RT_1D")
		)
		(pad "2" smd rect
			(at -0.889 0 270)
			(size 1.016 1.27)
			(layers "B.Cu" "B.Mask" "B.Paste")
			(net "GND")
		)
	)
)
